(kicad_pcb
	(version 20260206)
	(generator "pcbnew")
	(generator_version "10.0")
	(general
		(thickness 1.6)
		(legacy_teardrops no)
	)
	(paper "A4")
	(title_block
		(title "panther-plus-userver — 13130-1b_20150205.brd")
		(comment 1 "Honey Badger (Wiwynn) / footprints 199-206 of 1509")
	)
	(layers
		(0 "F.Cu" signal "TOP")
		(4 "In1.Cu" signal "L2")
		(6 "In2.Cu" signal "L3")
		(8 "In3.Cu" signal "L4")
		(10 "In4.Cu" signal "L5")
		(12 "In5.Cu" signal "L6")
		(14 "In6.Cu" signal "L7")
		(16 "In7.Cu" signal "L8")
		(18 "In8.Cu" signal "L9")
		(20 "In9.Cu" signal "L10")
		(22 "In10.Cu" signal "L11")
		(2 "B.Cu" signal "BOTTOM")
		(9 "F.Adhes" user "F.Adhesive")
		(11 "B.Adhes" user "B.Adhesive")
		(13 "F.Paste" user "Package Geometry/Pastemask Top")
		(15 "B.Paste" user "Package Geometry/Pastemask Bottom")
		(5 "F.SilkS" user "Ref Des/Silkscreen Top")
		(7 "B.SilkS" user "Ref Des/Silkscreen Bottom")
		(1 "F.Mask" user "Board Geometry/Soldermask Top")
		(3 "B.Mask" user "Board Geometry/Soldermask Bottom")
		(17 "Dwgs.User" user "User.Drawings")
		(19 "Cmts.User" user "User.Comments")
		(21 "Eco1.User" user "User.Eco1")
		(23 "Eco2.User" user "User.Eco2")
		(25 "Edge.Cuts" user "Board Geometry/Outline")
		(27 "Margin" user)
		(31 "F.CrtYd" user "Package Geometry/Place Bound Top")
		(29 "B.CrtYd" user "Package Geometry/Place Bound Bottom")
		(35 "F.Fab" user "Ref Des/Assembly Top")
		(33 "B.Fab" user "Ref Des/Assembly Bottom")
	)
	(footprint ""
		(layer "F.Cu")
		(at 183.642 -38.862 -90)
		(property "Reference" "PR126"
			(at 0 0 270)
			(layer "F.SilkS")
			(hide yes)
			(effects
				(font
					(size 1.27 1.27)
				)
			)
		)
		(property "Value" "10D7R2F-GP"
			(at 1.7907 -1.1176 270)
			(unlocked yes)
			(layer "F.Fab")
			(hide yes)
			(effects
				(font
					(size 1.016 1.016)
					(thickness 0.1524)
				)
			)
		)
		(property "Device Type" "R402H16"
			(at 1.7907 -2.6416 270)
			(unlocked yes)
			(layer "F.Fab")
			(hide yes)
			(effects
				(font
					(size 1.016 1.016)
					(thickness 0.1524)
				)
			)
		)
		(duplicate_pad_numbers_are_jumpers no)
		(fp_rect
			(start -0.381 0.8382)
			(end 0.381 -0.8382)
			(stroke
				(width 0)
				(type default)
			)
			(fill no)
			(layer "F.CrtYd")
		)
		(fp_rect
			(start -0.381 0.8382)
			(end 0.381 -0.8382)
			(stroke
				(width 0)
				(type default)
			)
			(fill no)
			(layer "F.Fab")
		)
		(pad "1" smd custom
			(at 0 -0.4318 270)
			(size 0.127 0.127)
			(layers "F.Cu" "F.Mask" "F.Paste")
			(net "SVID_DIO_A")
			(options
				(clearance outline)
				(anchor circle)
			)
			(primitives
				(gr_poly
					(pts
						(arc
							(start -0.2032 -0.2794)
							(mid -0.239121 -0.264521)
							(end -0.254 -0.2286)
						)
						(arc
							(start -0.254 0.2286)
							(mid -0.239121 0.264521)
							(end -0.2032 0.2794)
						)
						(arc
							(start 0.2032 0.2794)
							(mid 0.239121 0.264521)
							(end 0.254 0.2286)
						)
						(arc
							(start 0.254 -0.2286)
							(mid 0.239121 -0.264521)
							(end 0.2032 -0.2794)
						)
					)
					(width 0)
					(fill yes)
				)
			)
		)
		(pad "2" smd custom
			(at 0 0.4318 270)
			(size 0.127 0.127)
			(layers "F.Cu" "F.Mask" "F.Paste")
			(net "SVID_CPU_DATA")
			(options
				(clearance outline)
				(anchor circle)
			)
			(primitives
				(gr_poly
					(pts
						(arc
							(start -0.2032 -0.2794)
							(mid -0.239121 -0.264521)
							(end -0.254 -0.2286)
						)
						(arc
							(start -0.254 0.2286)
							(mid -0.239121 0.264521)
							(end -0.2032 0.2794)
						)
						(arc
							(start 0.2032 0.2794)
							(mid 0.239121 0.264521)
							(end 0.254 0.2286)
						)
						(arc
							(start 0.254 -0.2286)
							(mid 0.239121 -0.264521)
							(end 0.2032 -0.2794)
						)
					)
					(width 0)
					(fill yes)
				)
			)
		)
	)
	(footprint ""
		(layer "F.Cu")
		(at 26.035 -43.434 180)
		(property "Reference" "PC73"
			(at 0 0 180)
			(layer "F.SilkS")
			(hide yes)
			(effects
				(font
					(size 1.27 1.27)
				)
			)
		)
		(property "Value" "SC100U6D3V6MX-GP"
			(at 0.0127 -3.4671 180)
			(unlocked yes)
			(layer "F.Fab")
			(hide yes)
			(effects
				(font
					(size 1.016 1.016)
					(thickness 0.1524)
				)
			)
		)
		(property "Device Type" "C1206H71"
			(at 0.0127 -4.9911 180)
			(unlocked yes)
			(layer "F.Fab")
			(hide yes)
			(effects
				(font
					(size 1.016 1.016)
					(thickness 0.1524)
				)
			)
		)
		(duplicate_pad_numbers_are_jumpers no)
		(fp_rect
			(start -1.0541 1.9812)
			(end 1.0541 -1.9812)
			(stroke
				(width 0)
				(type default)
			)
			(fill no)
			(layer "F.CrtYd")
		)
		(fp_rect
			(start -1.0541 1.9812)
			(end 1.0541 -1.9812)
			(stroke
				(width 0)
				(type default)
			)
			(fill no)
			(layer "F.Fab")
		)
		(pad "1" smd rect
			(at 0 -1.3462 180)
			(size 1.8542 1.016)
			(layers "F.Cu" "F.Mask" "F.Paste")
			(net "P3V3_STBY_OUT")
		)
		(pad "2" smd rect
			(at 0 1.3462 180)
			(size 1.8542 1.016)
			(layers "F.Cu" "F.Mask" "F.Paste")
			(net "GND")
		)
	)
	(footprint ""
		(layer "F.Cu")
		(at 50.8 -46.355)
		(property "Reference" "R56"
			(at 0 0 0)
			(layer "F.SilkS")
			(hide yes)
			(effects
				(font
					(size 1.27 1.27)
				)
			)
		)
		(property "Value" "0R2J-2-GP"
			(at 0.064008 -3.993896 0)
			(unlocked yes)
			(layer "F.Fab")
			(hide yes)
			(effects
				(font
					(size 1.016 1.016)
					(thickness 0.1524)
				)
			)
		)
		(property "Device Type" "R402H16"
			(at 0.064008 -5.517896 0)
			(unlocked yes)
			(layer "F.Fab")
			(hide yes)
			(effects
				(font
					(size 1.016 1.016)
					(thickness 0.1524)
				)
			)
		)
		(duplicate_pad_numbers_are_jumpers no)
		(fp_rect
			(start -0.381 0.8382)
			(end 0.381 -0.8382)
			(stroke
				(width 0)
				(type default)
			)
			(fill no)
			(layer "F.CrtYd")
		)
		(fp_rect
			(start -0.381 0.8382)
			(end 0.381 -0.8382)
			(stroke
				(width 0)
				(type default)
			)
			(fill no)
			(layer "F.Fab")
		)
		(pad "1" smd custom
			(at 0 -0.4318)
			(size 0.127 0.127)
			(layers "F.Cu" "F.Mask" "F.Paste")
			(net "P1V0_STBY_PG")
			(options
				(clearance outline)
				(anchor circle)
			)
			(primitives
				(gr_poly
					(pts
						(arc
							(start -0.2032 -0.2794)
							(mid -0.239121 -0.264521)
							(end -0.254 -0.2286)
						)
						(arc
							(start -0.254 0.2286)
							(mid -0.239121 0.264521)
							(end -0.2032 0.2794)
						)
						(arc
							(start 0.2032 0.2794)
							(mid 0.239121 0.264521)
							(end 0.254 0.2286)
						)
						(arc
							(start 0.254 -0.2286)
							(mid 0.239121 -0.264521)
							(end 0.2032 -0.2794)
						)
					)
					(width 0)
					(fill yes)
				)
			)
		)
		(pad "2" smd custom
			(at 0 0.4318)
			(size 0.127 0.127)
			(layers "F.Cu" "F.Mask" "F.Paste")
			(net "SW_P3V3_CPU_LV_G2")
			(options
				(clearance outline)
				(anchor circle)
			)
			(primitives
				(gr_poly
					(pts
						(arc
							(start -0.2032 -0.2794)
							(mid -0.239121 -0.264521)
							(end -0.254 -0.2286)
						)
						(arc
							(start -0.254 0.2286)
							(mid -0.239121 0.264521)
							(end -0.2032 0.2794)
						)
						(arc
							(start 0.2032 0.2794)
							(mid 0.239121 0.264521)
							(end 0.254 0.2286)
						)
						(arc
							(start 0.254 -0.2286)
							(mid 0.239121 -0.264521)
							(end 0.2032 -0.2794)
						)
					)
					(width 0)
					(fill yes)
				)
			)
		)
	)
	(footprint ""
		(layer "F.Cu")
		(at 78.867 -59.944 180)
		(property "Reference" "C83"
			(at 0 0 180)
			(layer "F.SilkS")
			(hide yes)
			(effects
				(font
					(size 1.27 1.27)
				)
			)
		)
		(property "Value" "SCD1U16V2KX-3GP"
			(at 1.8923 -1.2065 180)
			(unlocked yes)
			(layer "F.Fab")
			(hide yes)
			(effects
				(font
					(size 1.016 1.016)
					(thickness 0.1524)
				)
			)
		)
		(property "Device Type" "C402H22"
			(at 1.8923 -2.7305 180)
			(unlocked yes)
			(layer "F.Fab")
			(hide yes)
			(effects
				(font
					(size 1.016 1.016)
					(thickness 0.1524)
				)
			)
		)
		(duplicate_pad_numbers_are_jumpers no)
		(fp_rect
			(start -0.381 0.7366)
			(end 0.381 -0.7366)
			(stroke
				(width 0)
				(type default)
			)
			(fill no)
			(layer "F.CrtYd")
		)
		(fp_rect
			(start -0.381 0.7366)
			(end 0.381 -0.7366)
			(stroke
				(width 0)
				(type default)
			)
			(fill no)
			(layer "F.Fab")
		)
		(pad "1" smd custom
			(at 0 -0.4572 180)
			(size 0.1143 0.1143)
			(layers "F.Cu" "F.Mask" "F.Paste")
			(net "VOL1_SEN_VREF")
			(options
				(clearance outline)
				(anchor circle)
			)
			(primitives
				(gr_poly
					(pts
						(arc
							(start -0.254 -0.1778)
							(mid -0.239121 -0.213721)
							(end -0.2032 -0.2286)
						)
						(arc
							(start 0.2032 -0.2286)
							(mid 0.239121 -0.213721)
							(end 0.254 -0.1778)
						)
						(arc
							(start 0.254 0.1778)
							(mid 0.239121 0.213721)
							(end 0.2032 0.2286)
						)
						(arc
							(start -0.2032 0.2286)
							(mid -0.239121 0.213721)
							(end -0.254 0.1778)
						)
					)
					(width 0)
					(fill yes)
				)
			)
		)
		(pad "2" smd custom
			(at 0 0.4572 180)
			(size 0.1143 0.1143)
			(layers "F.Cu" "F.Mask" "F.Paste")
			(net "GND")
			(options
				(clearance outline)
				(anchor circle)
			)
			(primitives
				(gr_poly
					(pts
						(arc
							(start -0.254 -0.1778)
							(mid -0.239121 -0.213721)
							(end -0.2032 -0.2286)
						)
						(arc
							(start 0.2032 -0.2286)
							(mid 0.239121 -0.213721)
							(end 0.254 -0.1778)
						)
						(arc
							(start 0.254 0.1778)
							(mid 0.239121 0.213721)
							(end 0.2032 0.2286)
						)
						(arc
							(start -0.2032 0.2286)
							(mid -0.239121 0.213721)
							(end -0.254 0.1778)
						)
					)
					(width 0)
					(fill yes)
				)
			)
		)
	)
	(footprint ""
		(layer "F.Cu")
		(at 185.039 -13.716 90)
		(property "Reference" "PC119"
			(at 0 0 90)
			(layer "F.SilkS")
			(hide yes)
			(effects
				(font
					(size 1.27 1.27)
				)
			)
		)
		(property "Value" "SC10U6D3V3MX-GP"
			(at 0 -2.8194 90)
			(unlocked yes)
			(layer "F.Fab")
			(hide yes)
			(effects
				(font
					(size 1.016 1.016)
					(thickness 0.1524)
				)
			)
		)
		(property "Device Type" "C603H38"
			(at 0 -4.3434 90)
			(unlocked yes)
			(layer "F.Fab")
			(hide yes)
			(effects
				(font
					(size 1.016 1.016)
					(thickness 0.1524)
				)
			)
		)
		(duplicate_pad_numbers_are_jumpers no)
		(fp_line
			(start -0.4064 0)
			(end 0.4064 0)
			(stroke
				(width 0.2286)
				(type default)
			)
			(layer "F.SilkS")
		)
		(fp_rect
			(start -0.635 1.1811)
			(end 0.635 -1.1811)
			(stroke
				(width 0)
				(type default)
			)
			(fill no)
			(layer "F.CrtYd")
		)
		(fp_rect
			(start -0.635 1.1811)
			(end 0.635 -1.1811)
			(stroke
				(width 0)
				(type default)
			)
			(fill no)
			(layer "F.Fab")
		)
		(pad "1" smd custom
			(at 0 -0.6604 90)
			(size 0.19685 0.19685)
			(layers "F.Cu" "F.Mask" "F.Paste")
			(net "GND")
			(options
				(clearance outline)
				(anchor circle)
			)
			(primitives
				(gr_poly
					(pts
						(arc
							(start 0.508 -0.2921)
							(mid 0.478242 -0.363942)
							(end 0.4064 -0.3937)
						)
						(arc
							(start -0.4064 -0.3937)
							(mid -0.478242 -0.363942)
							(end -0.508 -0.2921)
						)
						(arc
							(start -0.508 0.2921)
							(mid -0.478242 0.363942)
							(end -0.4064 0.3937)
						)
						(arc
							(start 0.4064 0.3937)
							(mid 0.478242 0.363942)
							(end 0.508 0.2921)
						)
					)
					(width 0)
					(fill yes)
				)
			)
		)
		(pad "2" smd custom
			(at 0 0.6604 90)
			(size 0.19685 0.19685)
			(layers "F.Cu" "F.Mask" "F.Paste")
			(net "PV_VTT_DDR_B")
			(options
				(clearance outline)
				(anchor circle)
			)
			(primitives
				(gr_poly
					(pts
						(arc
							(start 0.508 -0.2921)
							(mid 0.478242 -0.363942)
							(end 0.4064 -0.3937)
						)
						(arc
							(start -0.4064 -0.3937)
							(mid -0.478242 -0.363942)
							(end -0.508 -0.2921)
						)
						(arc
							(start -0.508 0.2921)
							(mid -0.478242 0.363942)
							(end -0.4064 0.3937)
						)
						(arc
							(start 0.4064 0.3937)
							(mid 0.478242 0.363942)
							(end 0.508 0.2921)
						)
					)
					(width 0)
					(fill yes)
				)
			)
		)
	)
	(footprint ""
		(layer "F.Cu")
		(at 43.0022 -49.1744 -90)
		(property "Reference" "R43"
			(at 0 0 270)
			(layer "F.SilkS")
			(hide yes)
			(effects
				(font
					(size 1.27 1.27)
				)
			)
		)
		(property "Value" "30KR2F-GP"
			(at 0.064008 -3.993896 270)
			(unlocked yes)
			(layer "F.Fab")
			(hide yes)
			(effects
				(font
					(size 1.016 1.016)
					(thickness 0.1524)
				)
			)
		)
		(property "Device Type" "R402H16"
			(at 0.064008 -5.517896 270)
			(unlocked yes)
			(layer "F.Fab")
			(hide yes)
			(effects
				(font
					(size 1.016 1.016)
					(thickness 0.1524)
				)
			)
		)
		(duplicate_pad_numbers_are_jumpers no)
		(fp_rect
			(start -0.381 0.8382)
			(end 0.381 -0.8382)
			(stroke
				(width 0)
				(type default)
			)
			(fill no)
			(layer "F.CrtYd")
		)
		(fp_rect
			(start -0.381 0.8382)
			(end 0.381 -0.8382)
			(stroke
				(width 0)
				(type default)
			)
			(fill no)
			(layer "F.Fab")
		)
		(pad "1" smd custom
			(at 0 -0.4318 270)
			(size 0.127 0.127)
			(layers "F.Cu" "F.Mask" "F.Paste")
			(net "P3V3_CPU")
			(options
				(clearance outline)
				(anchor circle)
			)
			(primitives
				(gr_poly
					(pts
						(arc
							(start -0.2032 -0.2794)
							(mid -0.239121 -0.264521)
							(end -0.254 -0.2286)
						)
						(arc
							(start -0.254 0.2286)
							(mid -0.239121 0.264521)
							(end -0.2032 0.2794)
						)
						(arc
							(start 0.2032 0.2794)
							(mid 0.239121 0.264521)
							(end 0.254 0.2286)
						)
						(arc
							(start 0.254 -0.2286)
							(mid 0.239121 -0.264521)
							(end 0.2032 -0.2794)
						)
					)
					(width 0)
					(fill yes)
				)
			)
		)
		(pad "2" smd custom
			(at 0 0.4318 270)
			(size 0.127 0.127)
			(layers "F.Cu" "F.Mask" "F.Paste")
			(net "P3V3_CPU_DELAY_IN")
			(options
				(clearance outline)
				(anchor circle)
			)
			(primitives
				(gr_poly
					(pts
						(arc
							(start -0.2032 -0.2794)
							(mid -0.239121 -0.264521)
							(end -0.254 -0.2286)
						)
						(arc
							(start -0.254 0.2286)
							(mid -0.239121 0.264521)
							(end -0.2032 0.2794)
						)
						(arc
							(start 0.2032 0.2794)
							(mid 0.239121 0.264521)
							(end 0.254 0.2286)
						)
						(arc
							(start 0.254 -0.2286)
							(mid 0.239121 -0.264521)
							(end 0.2032 -0.2794)
						)
					)
					(width 0)
					(fill yes)
				)
			)
		)
	)
	(footprint ""
		(layer "F.Cu")
		(at 141.0462 -53.2384)
		(property "Reference" "C356"
			(at 0 0 0)
			(layer "F.SilkS")
			(hide yes)
			(effects
				(font
					(size 1.27 1.27)
				)
			)
		)
		(property "Value" "SCD1U16V2KX-3GP"
			(at 1.8923 -1.2065 0)
			(unlocked yes)
			(layer "F.Fab")
			(hide yes)
			(effects
				(font
					(size 1.016 1.016)
					(thickness 0.1524)
				)
			)
		)
		(property "Device Type" "C402H22"
			(at 1.8923 -2.7305 0)
			(unlocked yes)
			(layer "F.Fab")
			(hide yes)
			(effects
				(font
					(size 1.016 1.016)
					(thickness 0.1524)
				)
			)
		)
		(duplicate_pad_numbers_are_jumpers no)
		(fp_rect
			(start -0.381 0.7366)
			(end 0.381 -0.7366)
			(stroke
				(width 0)
				(type default)
			)
			(fill no)
			(layer "F.CrtYd")
		)
		(fp_rect
			(start -0.381 0.7366)
			(end 0.381 -0.7366)
			(stroke
				(width 0)
				(type default)
			)
			(fill no)
			(layer "F.Fab")
		)
		(pad "1" smd custom
			(at 0 -0.4572)
			(size 0.1143 0.1143)
			(layers "F.Cu" "F.Mask" "F.Paste")
			(net "P3V3_STBY")
			(options
				(clearance outline)
				(anchor circle)
			)
			(primitives
				(gr_poly
					(pts
						(arc
							(start -0.254 -0.1778)
							(mid -0.239121 -0.213721)
							(end -0.2032 -0.2286)
						)
						(arc
							(start 0.2032 -0.2286)
							(mid 0.239121 -0.213721)
							(end 0.254 -0.1778)
						)
						(arc
							(start 0.254 0.1778)
							(mid 0.239121 0.213721)
							(end 0.2032 0.2286)
						)
						(arc
							(start -0.2032 0.2286)
							(mid -0.239121 0.213721)
							(end -0.254 0.1778)
						)
					)
					(width 0)
					(fill yes)
				)
			)
		)
		(pad "2" smd custom
			(at 0 0.4572)
			(size 0.1143 0.1143)
			(layers "F.Cu" "F.Mask" "F.Paste")
			(net "GND")
			(options
				(clearance outline)
				(anchor circle)
			)
			(primitives
				(gr_poly
					(pts
						(arc
							(start -0.254 -0.1778)
							(mid -0.239121 -0.213721)
							(end -0.2032 -0.2286)
						)
						(arc
							(start 0.2032 -0.2286)
							(mid 0.239121 -0.213721)
							(end 0.254 -0.1778)
						)
						(arc
							(start 0.254 0.1778)
							(mid 0.239121 0.213721)
							(end 0.2032 0.2286)
						)
						(arc
							(start -0.2032 0.2286)
							(mid -0.239121 0.213721)
							(end -0.254 0.1778)
						)
					)
					(width 0)
					(fill yes)
				)
			)
		)
	)
	(footprint ""
		(layer "F.Cu")
		(at 30.861 -33.02 180)
		(property "Reference" "C120"
			(at 0 0 180)
			(layer "F.SilkS")
			(hide yes)
			(effects
				(font
					(size 1.27 1.27)
				)
			)
		)
		(property "Value" "SCD1U16V2KX-3GP"
			(at 1.1811 -2.7051 180)
			(unlocked yes)
			(layer "F.Fab")
			(hide yes)
			(effects
				(font
					(size 1.016 1.016)
					(thickness 0.1524)
				)
			)
		)
		(property "Device Type" "C402H22"
			(at 1.1811 -4.2291 180)
			(unlocked yes)
			(layer "F.Fab")
			(hide yes)
			(effects
				(font
					(size 1.016 1.016)
					(thickness 0.1524)
				)
			)
		)
		(duplicate_pad_numbers_are_jumpers no)
		(fp_rect
			(start -0.381 0.7366)
			(end 0.381 -0.7366)
			(stroke
				(width 0)
				(type default)
			)
			(fill no)
			(layer "F.CrtYd")
		)
		(fp_rect
			(start -0.381 0.7366)
			(end 0.381 -0.7366)
			(stroke
				(width 0)
				(type default)
			)
			(fill no)
			(layer "F.Fab")
		)
		(pad "1" smd custom
			(at 0 -0.4572 180)
			(size 0.1143 0.1143)
			(layers "F.Cu" "F.Mask" "F.Paste")
			(net "XDP_RST_BTN_R#")
			(options
				(clearance outline)
				(anchor circle)
			)
			(primitives
				(gr_poly
					(pts
						(arc
							(start -0.254 -0.1778)
							(mid -0.239121 -0.213721)
							(end -0.2032 -0.2286)
						)
						(arc
							(start 0.2032 -0.2286)
							(mid 0.239121 -0.213721)
							(end 0.254 -0.1778)
						)
						(arc
							(start 0.254 0.1778)
							(mid 0.239121 0.213721)
							(end 0.2032 0.2286)
						)
						(arc
							(start -0.2032 0.2286)
							(mid -0.239121 0.213721)
							(end -0.254 0.1778)
						)
					)
					(width 0)
					(fill yes)
				)
			)
		)
		(pad "2" smd custom
			(at 0 0.4572 180)
			(size 0.1143 0.1143)
			(layers "F.Cu" "F.Mask" "F.Paste")
			(net "GND")
			(options
				(clearance outline)
				(anchor circle)
			)
			(primitives
				(gr_poly
					(pts
						(arc
							(start -0.254 -0.1778)
							(mid -0.239121 -0.213721)
							(end -0.2032 -0.2286)
						)
						(arc
							(start 0.2032 -0.2286)
							(mid 0.239121 -0.213721)
							(end 0.254 -0.1778)
						)
						(arc
							(start 0.254 0.1778)
							(mid 0.239121 0.213721)
							(end 0.2032 0.2286)
						)
						(arc
							(start -0.2032 0.2286)
							(mid -0.239121 0.213721)
							(end -0.254 0.1778)
						)
					)
					(width 0)
					(fill yes)
				)
			)
		)
	)
)
